# T6G (Grand Teton) — schematic netlist excerpt (pin names and nets, part order shuffled) for the footprints in the layout excerpt that follows; sources: Cadence DE-HDL packaged netlist, KiCad conversion of 04192023_DAF0TMB3IC0_F0TG_MB_C_brd_V02_OCP.brd

C2344  Q_CAP  0.1UF 25V 10% X7R  pkg 0402  page 133 : A = P3V3_AUX ; B = GND
R2566  Q_RES  0 5% CHIP  pkg 0402LF  page 250 : A = SMB_FRU_3V3AUX_SDA_R ; B = SMB_FRU_3V3AUX_SDA

(kicad_pcb
	(version 20260206)
	(generator "pcbnew")
	(generator_version "10.0")
	(general
		(thickness 1.6)
		(legacy_teardrops no)
	)
	(paper "A4")
	(title_block
		(title "04192023_DAF0TMB3IC0_F0TG_MB_C_brd_V02_OCP.brd")
		(comment 1 "Grand Teton / footprints 1144-1145 of 8354")
	)
	(layers
		(0 "F.Cu" signal "TOP")
		(4 "In1.Cu" signal "GND")
		(6 "In2.Cu" signal "IN1")
		(8 "In3.Cu" signal "GND1")
		(10 "In4.Cu" signal "IN2")
		(12 "In5.Cu" signal "GND2")
		(14 "In6.Cu" signal "IN3")
		(16 "In7.Cu" signal "GND3")
		(18 "In8.Cu" signal "VCC")
		(20 "In9.Cu" signal "VCC1")
		(22 "In10.Cu" signal "GND4")
		(24 "In11.Cu" signal "IN4")
		(26 "In12.Cu" signal "GND5")
		(28 "In13.Cu" signal "IN5")
		(30 "In14.Cu" signal "GND6")
		(32 "In15.Cu" signal "IN6")
		(34 "In16.Cu" signal "GND7")
		(2 "B.Cu" signal "BOTTOM")
		(9 "F.Adhes" user "F.Adhesive")
		(11 "B.Adhes" user "B.Adhesive")
		(13 "F.Paste" user "Package Geometry/Pastemask Top")
		(15 "B.Paste" user "Package Geometry/Pastemask Bottom")
		(5 "F.SilkS" user "Ref Des/Silkscreen Top")
		(7 "B.SilkS" user "Ref Des/Silkscreen Bottom")
		(1 "F.Mask" user "Board Geometry/Soldermask Top")
		(3 "B.Mask" user "Board Geometry/Soldermask Bottom")
		(17 "Dwgs.User" user "User.Drawings")
		(19 "Cmts.User" user "User.Comments")
		(21 "Eco1.User" user "User.Eco1")
		(23 "Eco2.User" user "User.Eco2")
		(25 "Edge.Cuts" user "Board Geometry/Outline")
		(27 "Margin" user)
		(31 "F.CrtYd" user "Package Geometry/Place Bound Top")
		(29 "B.CrtYd" user "Package Geometry/Place Bound Bottom")
		(35 "F.Fab" user "Ref Des/Assembly Top")
		(33 "B.Fab" user "Ref Des/Assembly Bottom")
	)
	(footprint ""
		(layer "F.Cu")
		(at 376.89028 -32.323532 -90)
		(property "Reference" "C2344"
			(at 0 0 270)
			(layer "F.SilkS")
			(hide yes)
			(effects
				(font
					(size 1.27 1.27)
				)
			)
		)
		(property "Value" ""
			(at 0 0 270)
			(layer "F.Fab")
			(effects
				(font
					(size 1.27 1.27)
				)
			)
		)
		(duplicate_pad_numbers_are_jumpers no)
		(fp_line
			(start -0.7874 0.4064)
			(end -0.7874 -0.4064)
			(stroke
				(width 0.1524)
				(type default)
			)
			(layer "F.SilkS")
		)
		(fp_line
			(start 0.7874 0.4064)
			(end -0.7874 0.4064)
			(stroke
				(width 0.1524)
				(type default)
			)
			(layer "F.SilkS")
		)
		(fp_line
			(start -0.7874 -0.4064)
			(end 0.7874 -0.4064)
			(stroke
				(width 0.1524)
				(type default)
			)
			(layer "F.SilkS")
		)
		(fp_line
			(start 0.7874 -0.4064)
			(end 0.7874 0.4064)
			(stroke
				(width 0.1524)
				(type default)
			)
			(layer "F.SilkS")
		)
		(fp_line
			(start -0.67945 0.3048)
			(end -0.67945 -0.305054)
			(stroke
				(width 0.1)
				(type default)
			)
			(layer "F.Fab")
		)
		(fp_line
			(start -0.12065 0.3048)
			(end -0.67945 0.3048)
			(stroke
				(width 0.1)
				(type default)
			)
			(layer "F.Fab")
		)
		(fp_line
			(start 0.120396 0.3048)
			(end 0.120396 0.2794)
			(stroke
				(width 0.1)
				(type default)
			)
			(layer "F.Fab")
		)
		(fp_line
			(start 0.67945 0.3048)
			(end 0.120396 0.3048)
			(stroke
				(width 0.1)
				(type default)
			)
			(layer "F.Fab")
		)
		(fp_line
			(start -0.12065 0.2794)
			(end -0.12065 0.3048)
			(stroke
				(width 0.1)
				(type default)
			)
			(layer "F.Fab")
		)
		(fp_line
			(start 0.120396 0.2794)
			(end -0.12065 0.2794)
			(stroke
				(width 0.1)
				(type default)
			)
			(layer "F.Fab")
		)
		(fp_line
			(start -0.12065 -0.2794)
			(end 0.12065 -0.2794)
			(stroke
				(width 0.1)
				(type default)
			)
			(layer "F.Fab")
		)
		(fp_line
			(start 0.12065 -0.2794)
			(end 0.12065 -0.3048)
			(stroke
				(width 0.1)
				(type default)
			)
			(layer "F.Fab")
		)
		(fp_line
			(start 0.12065 -0.3048)
			(end 0.67945 -0.3048)
			(stroke
				(width 0.1)
				(type default)
			)
			(layer "F.Fab")
		)
		(fp_line
			(start 0.67945 -0.3048)
			(end 0.67945 0.3048)
			(stroke
				(width 0.1)
				(type default)
			)
			(layer "F.Fab")
		)
		(fp_line
			(start -0.67945 -0.305054)
			(end -0.12065 -0.305054)
			(stroke
				(width 0.1)
				(type default)
			)
			(layer "F.Fab")
		)
		(fp_line
			(start -0.12065 -0.305054)
			(end -0.12065 -0.2794)
			(stroke
				(width 0.1)
				(type default)
			)
			(layer "F.Fab")
		)
		(pad "1" smd circle
			(at -0.40005 0 270)
			(size 0 0)
			(layers "F.Cu" "F.Mask" "F.Paste")
			(net "P3V3_AUX")
		)
		(pad "2" smd circle
			(at 0.40005 0 270)
			(size 0 0)
			(layers "F.Cu" "F.Mask" "F.Paste")
			(net "GND")
		)
	)
	(footprint ""
		(layer "F.Cu")
		(at 294.421052 -116.253514)
		(property "Reference" "R2566"
			(at 0 0 0)
			(layer "F.SilkS")
			(hide yes)
			(effects
				(font
					(size 1.27 1.27)
				)
			)
		)
		(property "Value" ""
			(at 0 0 0)
			(layer "F.Fab")
			(effects
				(font
					(size 1.27 1.27)
				)
			)
		)
		(duplicate_pad_numbers_are_jumpers no)
		(fp_line
			(start -0.7874 -0.4064)
			(end 0.7874 -0.4064)
			(stroke
				(width 0.1524)
				(type default)
			)
			(layer "F.SilkS")
		)
		(fp_line
			(start -0.7874 0.4064)
			(end -0.7874 -0.4064)
			(stroke
				(width 0.1524)
				(type default)
			)
			(layer "F.SilkS")
		)
		(fp_line
			(start 0.7874 -0.4064)
			(end 0.7874 0.4064)
			(stroke
				(width 0.1524)
				(type default)
			)
			(layer "F.SilkS")
		)
		(fp_line
			(start 0.7874 0.4064)
			(end -0.7874 0.4064)
			(stroke
				(width 0.1524)
				(type default)
			)
			(layer "F.SilkS")
		)
		(fp_line
			(start -0.67945 -0.305054)
			(end -0.12065 -0.305054)
			(stroke
				(width 0.1)
				(type default)
			)
			(layer "F.Fab")
		)
		(fp_line
			(start -0.67945 0.3048)
			(end -0.67945 -0.305054)
			(stroke
				(width 0.1)
				(type default)
			)
			(layer "F.Fab")
		)
		(fp_line
			(start -0.12065 -0.305054)
			(end -0.12065 -0.2794)
			(stroke
				(width 0.1)
				(type default)
			)
			(layer "F.Fab")
		)
		(fp_line
			(start -0.12065 -0.2794)
			(end 0.12065 -0.2794)
			(stroke
				(width 0.1)
				(type default)
			)
			(layer "F.Fab")
		)
		(fp_line
			(start -0.12065 0.2794)
			(end -0.12065 0.3048)
			(stroke
				(width 0.1)
				(type default)
			)
			(layer "F.Fab")
		)
		(fp_line
			(start -0.12065 0.3048)
			(end -0.67945 0.3048)
			(stroke
				(width 0.1)
				(type default)
			)
			(layer "F.Fab")
		)
		(fp_line
			(start 0.120396 0.2794)
			(end -0.12065 0.2794)
			(stroke
				(width 0.1)
				(type default)
			)
			(layer "F.Fab")
		)
		(fp_line
			(start 0.120396 0.3048)
			(end 0.120396 0.2794)
			(stroke
				(width 0.1)
				(type default)
			)
			(layer "F.Fab")
		)
		(fp_line
			(start 0.12065 -0.3048)
			(end 0.67945 -0.3048)
			(stroke
				(width 0.1)
				(type default)
			)
			(layer "F.Fab")
		)
		(fp_line
			(start 0.12065 -0.2794)
			(end 0.12065 -0.3048)
			(stroke
				(width 0.1)
				(type default)
			)
			(layer "F.Fab")
		)
		(fp_line
			(start 0.67945 -0.3048)
			(end 0.67945 0.3048)
			(stroke
				(width 0.1)
				(type default)
			)
			(layer "F.Fab")
		)
		(fp_line
			(start 0.67945 0.3048)
			(end 0.120396 0.3048)
			(stroke
				(width 0.1)
				(type default)
			)
			(layer "F.Fab")
		)
		(pad "1" smd circle
			(at -0.40005 0)
			(size 0 0)
			(layers "F.Cu" "F.Mask" "F.Paste")
			(net "SMB_FRU_3V3AUX_SDA_R")
		)
		(pad "2" smd circle
			(at 0.40005 0)
			(size 0 0)
			(layers "F.Cu" "F.Mask" "F.Paste")
			(net "SMB_FRU_3V3AUX_SDA")
		)
	)
)
